# BASEBOARD_FAB2 (Tioga Pass) — schematic netlist excerpt (pin names and nets, part order shuffled) for the footprints in the layout excerpt that follows; sources: Cadence DE-HDL packaged netlist, KiCad conversion of Wiwynn_Tioga_Pass_MB.brd

R4D8  RES  27.4 1% CHIP  pkg 0402  page 103 : A = CLK_100M_CPU0_RC_REFCLK0_R_DP ; B = CLK_100M_CPU0_RC_REFCLK0_DP
R4G10  RES  1.0K 0.1% CHIP  pkg 0402  page 233 : A = VSENSE_PVPP_GHJ ; B = VR_COMP_PVPP_GHJ
R7D26  RES  1.00K 1% CHIP  pkg 0402  page 92 : A = PD_GTL2104_DIR_0 ; B = GND

(kicad_pcb
	(version 20260206)
	(generator "pcbnew")
	(generator_version "10.0")
	(general
		(thickness 1.6)
		(legacy_teardrops no)
	)
	(paper "A4")
	(title_block
		(title "Wiwynn_Tioga_Pass_MB.brd")
		(comment 1 "Tioga Pass / footprints 2197-2199 of 4770")
	)
	(layers
		(0 "F.Cu" signal "TOP")
		(4 "In1.Cu" signal "L2GND")
		(6 "In2.Cu" signal "L3")
		(8 "In3.Cu" signal "L4GND")
		(10 "In4.Cu" signal "L5")
		(12 "In5.Cu" signal "L6GND")
		(14 "In6.Cu" signal "L7VCC")
		(16 "In7.Cu" signal "L8VCC")
		(18 "In8.Cu" signal "L9GND")
		(20 "In9.Cu" signal "L10")
		(22 "In10.Cu" signal "L11GND")
		(24 "In11.Cu" signal "L12")
		(26 "In12.Cu" signal "L13GND")
		(2 "B.Cu" signal "BOTTOM")
		(9 "F.Adhes" user "F.Adhesive")
		(11 "B.Adhes" user "B.Adhesive")
		(13 "F.Paste" user "Package Geometry/Pastemask Top")
		(15 "B.Paste" user "Package Geometry/Pastemask Bottom")
		(5 "F.SilkS" user "Ref Des/Silkscreen Top")
		(7 "B.SilkS" user "Ref Des/Silkscreen Bottom")
		(1 "F.Mask" user "Board Geometry/Soldermask Top")
		(3 "B.Mask" user "Board Geometry/Soldermask Bottom")
		(17 "Dwgs.User" user "User.Drawings")
		(19 "Cmts.User" user "User.Comments")
		(21 "Eco1.User" user "User.Eco1")
		(23 "Eco2.User" user "User.Eco2")
		(25 "Edge.Cuts" user "Board Geometry/Outline")
		(27 "Margin" user)
		(31 "F.CrtYd" user "Package Geometry/Place Bound Top")
		(29 "B.CrtYd" user "Package Geometry/Place Bound Bottom")
		(35 "F.Fab" user "Ref Des/Assembly Top")
		(33 "B.Fab" user "Ref Des/Assembly Bottom")
	)
	(footprint ""
		(layer "F.Cu")
		(at 173.736 -86.868 180)
		(property "Reference" "R4D8"
			(at 0 0 180)
			(layer "F.SilkS")
			(hide yes)
			(effects
				(font
					(size 1.27 1.27)
				)
			)
		)
		(property "Value" ""
			(at 0 0 180)
			(layer "F.Fab")
			(effects
				(font
					(size 1.27 1.27)
				)
			)
		)
		(duplicate_pad_numbers_are_jumpers no)
		(fp_poly
			(pts
				(xy -0.2794 -0.1016) (xy 0.2794 -0.1016) (xy 0.2794 0.9906) (xy -0.2794 0.9906)
			)
			(stroke
				(width 0)
				(type default)
			)
			(fill no)
			(layer "F.CrtYd")
		)
		(fp_line
			(start 0.2794 0.9906)
			(end 0.2794 -0.1016)
			(stroke
				(width 0.1)
				(type default)
			)
			(layer "F.Fab")
		)
		(fp_line
			(start 0.2794 -0.1016)
			(end -0.2794 -0.1016)
			(stroke
				(width 0.1)
				(type default)
			)
			(layer "F.Fab")
		)
		(fp_line
			(start -0.2794 0.9906)
			(end 0.2794 0.9906)
			(stroke
				(width 0.1)
				(type default)
			)
			(layer "F.Fab")
		)
		(fp_line
			(start -0.2794 -0.1016)
			(end -0.2794 0.9906)
			(stroke
				(width 0.1)
				(type default)
			)
			(layer "F.Fab")
		)
		(pad "1" smd rect
			(at 0 0 180)
			(size 0.508 0.508)
			(layers "F.Cu" "F.Mask" "F.Paste")
			(net "CLK_100M_CPU0_RC_REFCLK0_R_DP")
		)
		(pad "2" smd rect
			(at 0 0.889 180)
			(size 0.508 0.508)
			(layers "F.Cu" "F.Mask" "F.Paste")
			(net "CLK_100M_CPU0_RC_REFCLK0_DP")
		)
		(zone
			(layer "F.Cu")
			(hatch none 0.5)
			(connect_pads
				(clearance 0)
			)
			(min_thickness 0.25)
			(keepout
				(tracks not_allowed)
				(vias allowed)
				(pads allowed)
				(copperpour not_allowed)
				(footprints allowed)
			)
			(placement
				(enabled no)
				(sheetname "")
			)
			(fill
				(thermal_gap 0.5)
				(thermal_bridge_width 0.5)
				(island_removal_mode 0)
			)
			(polygon
				(pts
					(xy 173.99 -87.503) (xy 173.482 -87.503) (xy 173.482 -87.122) (xy 173.99 -87.122)
				)
			)
		)
		(zone
			(layer "F.Cu")
			(hatch none 0.5)
			(connect_pads
				(clearance 0)
			)
			(min_thickness 0.25)
			(keepout
				(tracks allowed)
				(vias not_allowed)
				(pads allowed)
				(copperpour not_allowed)
				(footprints allowed)
			)
			(placement
				(enabled no)
				(sheetname "")
			)
			(fill
				(thermal_gap 0.5)
				(thermal_bridge_width 0.5)
				(island_removal_mode 0)
			)
			(polygon
				(pts
					(xy 173.99 -87.122) (xy 173.482 -87.122) (xy 173.482 -87.503) (xy 173.99 -87.503)
				)
			)
		)
	)
	(footprint ""
		(layer "F.Cu")
		(at 386.2705 -79.8322 90)
		(property "Reference" "R7D26"
			(at 0 0 90)
			(layer "F.SilkS")
			(hide yes)
			(effects
				(font
					(size 1.27 1.27)
				)
			)
		)
		(property "Value" ""
			(at 0 0 90)
			(layer "F.Fab")
			(effects
				(font
					(size 1.27 1.27)
				)
			)
		)
		(duplicate_pad_numbers_are_jumpers no)
		(fp_poly
			(pts
				(xy -0.2794 -0.1016) (xy 0.2794 -0.1016) (xy 0.2794 0.9906) (xy -0.2794 0.9906)
			)
			(stroke
				(width 0)
				(type default)
			)
			(fill no)
			(layer "F.CrtYd")
		)
		(fp_line
			(start 0.2794 -0.1016)
			(end -0.2794 -0.1016)
			(stroke
				(width 0.1)
				(type default)
			)
			(layer "F.Fab")
		)
		(fp_line
			(start -0.2794 -0.1016)
			(end -0.2794 0.9906)
			(stroke
				(width 0.1)
				(type default)
			)
			(layer "F.Fab")
		)
		(fp_line
			(start 0.2794 0.9906)
			(end 0.2794 -0.1016)
			(stroke
				(width 0.1)
				(type default)
			)
			(layer "F.Fab")
		)
		(fp_line
			(start -0.2794 0.9906)
			(end 0.2794 0.9906)
			(stroke
				(width 0.1)
				(type default)
			)
			(layer "F.Fab")
		)
		(pad "1" smd rect
			(at 0 0 90)
			(size 0.508 0.508)
			(layers "F.Cu" "F.Mask" "F.Paste")
			(net "PD_GTL2104_DIR_0")
		)
		(pad "2" smd rect
			(at 0 0.889 90)
			(size 0.508 0.508)
			(layers "F.Cu" "F.Mask" "F.Paste")
			(net "GND")
		)
		(zone
			(layer "F.Cu")
			(hatch none 0.5)
			(connect_pads
				(clearance 0)
			)
			(min_thickness 0.25)
			(keepout
				(tracks allowed)
				(vias not_allowed)
				(pads allowed)
				(copperpour not_allowed)
				(footprints allowed)
			)
			(placement
				(enabled no)
				(sheetname "")
			)
			(fill
				(thermal_gap 0.5)
				(thermal_bridge_width 0.5)
				(island_removal_mode 0)
			)
			(polygon
				(pts
					(xy 386.5245 -79.5782) (xy 386.5245 -80.0862) (xy 386.9055 -80.0862) (xy 386.9055 -79.5782)
				)
			)
		)
		(zone
			(layer "F.Cu")
			(hatch none 0.5)
			(connect_pads
				(clearance 0)
			)
			(min_thickness 0.25)
			(keepout
				(tracks not_allowed)
				(vias allowed)
				(pads allowed)
				(copperpour not_allowed)
				(footprints allowed)
			)
			(placement
				(enabled no)
				(sheetname "")
			)
			(fill
				(thermal_gap 0.5)
				(thermal_bridge_width 0.5)
				(island_removal_mode 0)
			)
			(polygon
				(pts
					(xy 386.9055 -79.5782) (xy 386.9055 -80.0862) (xy 386.5245 -80.0862) (xy 386.5245 -79.5782)
				)
			)
		)
	)
	(footprint ""
		(layer "F.Cu")
		(at 168.7322 -8.0137)
		(property "Reference" "R4G10"
			(at 0 0 0)
			(layer "F.SilkS")
			(hide yes)
			(effects
				(font
					(size 1.27 1.27)
				)
			)
		)
		(property "Value" ""
			(at 0 0 0)
			(layer "F.Fab")
			(effects
				(font
					(size 1.27 1.27)
				)
			)
		)
		(duplicate_pad_numbers_are_jumpers no)
		(fp_poly
			(pts
				(xy -0.2794 -0.1016) (xy 0.2794 -0.1016) (xy 0.2794 0.9906) (xy -0.2794 0.9906)
			)
			(stroke
				(width 0)
				(type default)
			)
			(fill no)
			(layer "F.CrtYd")
		)
		(fp_line
			(start -0.2794 -0.1016)
			(end -0.2794 0.9906)
			(stroke
				(width 0.1)
				(type default)
			)
			(layer "F.Fab")
		)
		(fp_line
			(start -0.2794 0.9906)
			(end 0.2794 0.9906)
			(stroke
				(width 0.1)
				(type default)
			)
			(layer "F.Fab")
		)
		(fp_line
			(start 0.2794 -0.1016)
			(end -0.2794 -0.1016)
			(stroke
				(width 0.1)
				(type default)
			)
			(layer "F.Fab")
		)
		(fp_line
			(start 0.2794 0.9906)
			(end 0.2794 -0.1016)
			(stroke
				(width 0.1)
				(type default)
			)
			(layer "F.Fab")
		)
		(pad "1" smd rect
			(at 0 0)
			(size 0.508 0.508)
			(layers "F.Cu" "F.Mask" "F.Paste")
			(net "VSENSE_PVPP_GHJ")
		)
		(pad "2" smd rect
			(at 0 0.889)
			(size 0.508 0.508)
			(layers "F.Cu" "F.Mask" "F.Paste")
			(net "VR_COMP_PVPP_GHJ")
		)
		(zone
			(layer "F.Cu")
			(hatch none 0.5)
			(connect_pads
				(clearance 0)
			)
			(min_thickness 0.25)
			(keepout
				(tracks allowed)
				(vias not_allowed)
				(pads allowed)
				(copperpour not_allowed)
				(footprints allowed)
			)
			(placement
				(enabled no)
				(sheetname "")
			)
			(fill
				(thermal_gap 0.5)
				(thermal_bridge_width 0.5)
				(island_removal_mode 0)
			)
			(polygon
				(pts
					(xy 168.4782 -7.7597) (xy 168.9862 -7.7597) (xy 168.9862 -7.3787) (xy 168.4782 -7.3787)
				)
			)
		)
		(zone
			(layer "F.Cu")
			(hatch none 0.5)
			(connect_pads
				(clearance 0)
			)
			(min_thickness 0.25)
			(keepout
				(tracks not_allowed)
				(vias allowed)
				(pads allowed)
				(copperpour not_allowed)
				(footprints allowed)
			)
			(placement
				(enabled no)
				(sheetname "")
			)
			(fill
				(thermal_gap 0.5)
				(thermal_bridge_width 0.5)
				(island_removal_mode 0)
			)
			(polygon
				(pts
					(xy 168.4782 -7.3787) (xy 168.9862 -7.3787) (xy 168.9862 -7.7597) (xy 168.4782 -7.7597)
				)
			)
		)
	)
)
